(kicad_sch
	(version 20250114)
	(generator "eeschema")
	(generator_version "9.0")
	(paper "A3")
	(title_block
		(title "SO-DIMM DDR5 Tester")
		(date "2025-11-26")
		(rev "1.3.0")
		(company "Antmicro Ltd.")
		(comment 1 "www.antmicro.com")
		(comment 2 "Antmicro Ltd")
	)
	(text "Clock source"
		(exclude_from_sim no)
		(at 17.78 239.395 0)
		(effects
			(font
				(size 2.54 2.54)
				(thickness 0.4978)
				(bold yes)
			)
			(justify left bottom)
		)
	)
	(text "BANK 16"
		(exclude_from_sim no)
		(at 13.97 18.415 0)
		(effects
			(font
				(size 2.4892 2.4892)
				(thickness 0.4978)
				(bold yes)
			)
			(justify left bottom)
		)
	)
	(text "VCCO (HR banks) max: 3.6V"
		(exclude_from_sim no)
		(at 13.97 21.59 0)
		(effects
			(font
				(size 1.27 1.27)
			)
			(justify left bottom)
		)
	)
	(junction
		(at 34.925 257.81)
		(diameter 0)
		(color 0 0 0 0)
	)
	(junction
		(at 26.035 257.81)
		(diameter 0)
		(color 0 0 0 0)
	)
	(no_connect
		(at 185.42 201.93)
	)
	(no_connect
		(at 185.42 80.01)
	)
	(no_connect
		(at 185.42 130.81)
	)
	(no_connect
		(at 185.42 97.79)
	)
	(no_connect
		(at 185.42 95.25)
	)
	(no_connect
		(at 185.42 87.63)
	)
	(no_connect
		(at 185.42 90.17)
	)
	(no_connect
		(at 185.42 82.55)
	)
	(no_connect
		(at 185.42 128.27)
	)
	(no_connect
		(at 185.42 107.95)
	)
	(no_connect
		(at 185.42 92.71)
	)
	(no_connect
		(at 185.42 102.87)
	)
	(no_connect
		(at 185.42 173.99)
	)
	(no_connect
		(at 185.42 143.51)
	)
	(no_connect
		(at 185.42 146.05)
	)
	(no_connect
		(at 185.42 105.41)
	)
	(no_connect
		(at 185.42 161.29)
	)
	(no_connect
		(at 185.42 156.21)
	)
	(no_connect
		(at 185.42 176.53)
	)
	(no_connect
		(at 185.42 100.33)
	)
	(no_connect
		(at 185.42 168.91)
	)
	(no_connect
		(at 185.42 151.13)
	)
	(no_connect
		(at 185.42 166.37)
	)
	(no_connect
		(at 185.42 133.35)
	)
	(no_connect
		(at 185.42 163.83)
	)
	(no_connect
		(at 185.42 120.65)
	)
	(no_connect
		(at 185.42 179.07)
	)
	(no_connect
		(at 185.42 158.75)
	)
	(no_connect
		(at 185.42 77.47)
	)
	(no_connect
		(at 185.42 153.67)
	)
	(no_connect
		(at 185.42 148.59)
	)
	(no_connect
		(at 185.42 85.09)
	)
	(no_connect
		(at 185.42 171.45)
	)
	(bus_entry
		(at 154.305 135.89)
		(size -2.54 -2.54)
		(stroke
			(width 0)
			(type default)
		)
	)
	(bus_entry
		(at 154.305 118.11)
		(size -2.54 -2.54)
		(stroke
			(width 0)
			(type default)
		)
	)
	(bus_entry
		(at 154.305 115.57)
		(size -2.54 -2.54)
		(stroke
			(width 0)
			(type default)
		)
	)
	(bus_entry
		(at 173.99 184.15)
		(size -2.54 -2.54)
		(stroke
			(width 0)
			(type default)
		)
	)
	(bus_entry
		(at 154.305 125.73)
		(size -2.54 -2.54)
		(stroke
			(width 0)
			(type default)
		)
	)
	(bus_entry
		(at 173.99 196.85)
		(size -2.54 -2.54)
		(stroke
			(width 0)
			(type default)
		)
	)
	(bus_entry
		(at 173.99 186.69)
		(size -2.54 -2.54)
		(stroke
			(width 0)
			(type default)
		)
	)
	(bus_entry
		(at 154.305 110.49)
		(size -2.54 -2.54)
		(stroke
			(width 0)
			(type default)
		)
	)
	(bus_entry
		(at 173.99 194.31)
		(size -2.54 -2.54)
		(stroke
			(width 0)
			(type default)
		)
	)
	(bus_entry
		(at 154.305 138.43)
		(size -2.54 -2.54)
		(stroke
			(width 0)
			(type default)
		)
	)
	(bus_entry
		(at 173.99 189.23)
		(size -2.54 -2.54)
		(stroke
			(width 0)
			(type default)
		)
	)
	(bus_entry
		(at 154.305 113.03)
		(size -2.54 -2.54)
		(stroke
			(width 0)
			(type default)
		)
	)
	(bus_entry
		(at 173.99 181.61)
		(size -2.54 -2.54)
		(stroke
			(width 0)
			(type default)
		)
	)
	(bus_entry
		(at 173.99 191.77)
		(size -2.54 -2.54)
		(stroke
			(width 0)
			(type default)
		)
	)
	(bus_entry
		(at 173.99 199.39)
		(size -2.54 -2.54)
		(stroke
			(width 0)
			(type default)
		)
	)
	(wire
		(pts
			(xy 154.305 113.03) (xy 185.42 113.03)
		)
		(stroke
			(width 0)
			(type default)
		)
	)
	(bus
		(pts
			(xy 149.225 106.045) (xy 151.13 106.045)
		)
		(stroke
			(width 0)
			(type default)
		)
	)
	(bus
		(pts
			(xy 171.45 177.8) (xy 171.45 179.07)
		)
		(stroke
			(width 0)
			(type default)
		)
	)
	(bus
		(pts
			(xy 171.45 194.31) (xy 171.45 196.85)
		)
		(stroke
			(width 0)
			(type default)
		)
	)
	(bus
		(pts
			(xy 171.45 186.69) (xy 171.45 189.23)
		)
		(stroke
			(width 0)
			(type default)
		)
	)
	(bus
		(pts
			(xy 151.765 115.57) (xy 151.765 123.19)
		)
		(stroke
			(width 0)
			(type default)
		)
	)
	(bus
		(pts
			(xy 151.765 133.35) (xy 151.765 135.89)
		)
		(stroke
			(width 0)
			(type default)
		)
	)
	(bus
		(pts
			(xy 168.91 177.165) (xy 170.815 177.165)
		)
		(stroke
			(width 0)
			(type default)
		)
	)
	(bus
		(pts
			(xy 170.815 177.165) (xy 171.45 177.8)
		)
		(stroke
			(width 0)
			(type default)
		)
	)
	(wire
		(pts
			(xy 185.42 189.23) (xy 173.99 189.23)
		)
		(stroke
			(width 0)
			(type default)
		)
	)
	(bus
		(pts
			(xy 151.765 123.19) (xy 151.765 133.35)
		)
		(stroke
			(width 0)
			(type default)
		)
	)
	(wire
		(pts
			(xy 26.035 267.335) (xy 26.035 264.795)
		)
		(stroke
			(width 0)
			(type default)
		)
	)
	(wire
		(pts
			(xy 185.42 186.69) (xy 173.99 186.69)
		)
		(stroke
			(width 0)
			(type default)
		)
	)
	(wire
		(pts
			(xy 184.15 71.12) (xy 184.15 72.39)
		)
		(stroke
			(width 0)
			(type default)
		)
	)
	(bus
		(pts
			(xy 151.13 106.045) (xy 151.765 106.68)
		)
		(stroke
			(width 0)
			(type default)
		)
	)
	(wire
		(pts
			(xy 154.305 135.89) (xy 185.42 135.89)
		)
		(stroke
			(width 0)
			(type default)
		)
	)
	(wire
		(pts
			(xy 154.305 138.43) (xy 185.42 138.43)
		)
		(stroke
			(width 0)
			(type default)
		)
	)
	(wire
		(pts
			(xy 34.29 262.89) (xy 34.29 267.335)
		)
		(stroke
			(width 0)
			(type default)
		)
	)
	(wire
		(pts
			(xy 154.305 115.57) (xy 185.42 115.57)
		)
		(stroke
			(width 0)
			(type default)
		)
	)
	(bus
		(pts
			(xy 171.45 191.77) (xy 171.45 194.31)
		)
		(stroke
			(width 0)
			(type default)
		)
	)
	(bus
		(pts
			(xy 151.765 110.49) (xy 151.765 113.03)
		)
		(stroke
			(width 0)
			(type default)
		)
	)
	(bus
		(pts
			(xy 151.765 107.95) (xy 151.765 110.49)
		)
		(stroke
			(width 0)
			(type default)
		)
	)
	(wire
		(pts
			(xy 176.53 140.97) (xy 185.42 140.97)
		)
		(stroke
			(width 0)
			(type default)
		)
	)
	(bus
		(pts
			(xy 171.45 189.23) (xy 171.45 191.77)
		)
		(stroke
			(width 0)
			(type default)
		)
	)
	(wire
		(pts
			(xy 26.035 257.81) (xy 34.925 257.81)
		)
		(stroke
			(width 0)
			(type default)
		)
	)
	(bus
		(pts
			(xy 171.45 181.61) (xy 171.45 184.15)
		)
		(stroke
			(width 0)
			(type default)
		)
	)
	(wire
		(pts
			(xy 185.42 181.61) (xy 173.99 181.61)
		)
		(stroke
			(width 0)
			(type default)
		)
	)
	(wire
		(pts
			(xy 185.42 72.39) (xy 184.15 72.39)
		)
		(stroke
			(width 0)
			(type default)
		)
	)
	(wire
		(pts
			(xy 185.42 196.85) (xy 173.99 196.85)
		)
		(stroke
			(width 0)
			(type default)
		)
	)
	(wire
		(pts
			(xy 154.305 125.73) (xy 185.42 125.73)
		)
		(stroke
			(width 0)
			(type default)
		)
	)
	(wire
		(pts
			(xy 185.42 194.31) (xy 173.99 194.31)
		)
		(stroke
			(width 0)
			(type default)
		)
	)
	(wire
		(pts
			(xy 26.035 255.905) (xy 26.035 257.81)
		)
		(stroke
			(width 0)
			(type default)
		)
	)
	(wire
		(pts
			(xy 34.925 260.35) (xy 34.925 257.81)
		)
		(stroke
			(width 0)
			(type default)
		)
	)
	(wire
		(pts
			(xy 26.035 259.715) (xy 26.035 257.81)
		)
		(stroke
			(width 0)
			(type default)
		)
	)
	(bus
		(pts
			(xy 171.45 179.07) (xy 171.45 181.61)
		)
		(stroke
			(width 0)
			(type default)
		)
	)
	(bus
		(pts
			(xy 151.765 113.03) (xy 151.765 115.57)
		)
		(stroke
			(width 0)
			(type default)
		)
	)
	(wire
		(pts
			(xy 36.83 262.89) (xy 34.29 262.89)
		)
		(stroke
			(width 0)
			(type default)
		)
	)
	(bus
		(pts
			(xy 151.765 106.68) (xy 151.765 107.95)
		)
		(stroke
			(width 0)
			(type default)
		)
	)
	(wire
		(pts
			(xy 184.15 123.19) (xy 185.42 123.19)
		)
		(stroke
			(width 0)
			(type default)
		)
	)
	(wire
		(pts
			(xy 34.925 257.81) (xy 36.83 257.81)
		)
		(stroke
			(width 0)
			(type default)
		)
	)
	(wire
		(pts
			(xy 185.42 184.15) (xy 173.99 184.15)
		)
		(stroke
			(width 0)
			(type default)
		)
	)
	(wire
		(pts
			(xy 154.305 118.11) (xy 185.42 118.11)
		)
		(stroke
			(width 0)
			(type default)
		)
	)
	(wire
		(pts
			(xy 185.42 191.77) (xy 173.99 191.77)
		)
		(stroke
			(width 0)
			(type default)
		)
	)
	(wire
		(pts
			(xy 154.305 110.49) (xy 185.42 110.49)
		)
		(stroke
			(width 0)
			(type default)
		)
	)
	(wire
		(pts
			(xy 55.88 257.81) (xy 65.405 257.81)
		)
		(stroke
			(width 0)
			(type default)
		)
	)
	(bus
		(pts
			(xy 171.45 184.15) (xy 171.45 186.69)
		)
		(stroke
			(width 0)
			(type default)
		)
	)
	(wire
		(pts
			(xy 185.42 199.39) (xy 173.99 199.39)
		)
		(stroke
			(width 0)
			(type default)
		)
	)
	(wire
		(pts
			(xy 36.83 260.35) (xy 34.925 260.35)
		)
		(stroke
			(width 0)
			(type default)
		)
	)
	(label "SD.DAT0"
		(at 154.305 135.89 0)
		(effects
			(font
				(size 1.27 1.27)
			)
			(justify left bottom)
		)
	)
	(label "SD.CMD"
		(at 154.305 118.11 0)
		(effects
			(font
				(size 1.27 1.27)
			)
			(justify left bottom)
		)
	)
	(label "GCLK100"
		(at 176.53 140.97 0)
		(effects
			(font
				(size 1.27 1.27)
			)
			(justify left bottom)
		)
	)
	(label "SD.DAT1"
		(at 154.305 113.03 0)
		(effects
			(font
				(size 1.27 1.27)
			)
			(justify left bottom)
		)
	)
	(label "SD.CD"
		(at 154.305 110.49 0)
		(effects
			(font
				(size 1.27 1.27)
			)
			(justify left bottom)
		)
	)
	(label "SD.CLK"
		(at 154.305 138.43 0)
		(effects
			(font
				(size 1.27 1.27)
			)
			(justify left bottom)
		)
	)
	(label "GCLK100"
		(at 65.405 257.81 180)
		(effects
			(font
				(size 1.27 1.27)
			)
			(justify right bottom)
		)
	)
	(label "HDMI.D2_P"
		(at 173.99 186.69 0)
		(effects
			(font
				(size 1.27 1.27)
			)
			(justify left bottom)
		)
	)
	(label "HDMI.D2_N"
		(at 173.99 189.23 0)
		(effects
			(font
				(size 1.27 1.27)
			)
			(justify left bottom)
		)
	)
	(label "SD.DAT3"
		(at 154.305 115.57 0)
		(effects
			(font
				(size 1.27 1.27)
			)
			(justify left bottom)
		)
	)
	(label "HDMI.CLK_N"
		(at 173.99 194.31 0)
		(effects
			(font
				(size 1.27 1.27)
			)
			(justify left bottom)
		)
	)
	(label "HDMI.CLK_P"
		(at 173.99 191.77 0)
		(effects
			(font
				(size 1.27 1.27)
			)
			(justify left bottom)
		)
	)
	(label "HDMI.D0_P"
		(at 173.99 181.61 0)
		(effects
			(font
				(size 1.27 1.27)
			)
			(justify left bottom)
		)
	)
	(label "HDMI.D0_N"
		(at 173.99 184.15 0)
		(effects
			(font
				(size 1.27 1.27)
			)
			(justify left bottom)
		)
	)
	(label "HDMI.D1_P"
		(at 173.99 196.85 0)
		(effects
			(font
				(size 1.27 1.27)
			)
			(justify left bottom)
		)
	)
	(label "SD.DAT2"
		(at 154.305 125.73 0)
		(effects
			(font
				(size 1.27 1.27)
			)
			(justify left bottom)
		)
	)
	(label "HDMI.D1_N"
		(at 173.99 199.39 0)
		(effects
			(font
				(size 1.27 1.27)
			)
			(justify left bottom)
		)
	)
	(global_label "PCIE.PWRGD"
		(shape input)
		(at 184.15 123.19 180)
		(fields_autoplaced yes)
		(effects
			(font
				(size 1.27 1.27)
			)
			(justify right)
		)
		(property "Intersheetrefs" "${INTERSHEET_REFS}"
			(at 170.3958 123.2694 0)
			(effects
				(font
					(size 1.27 1.27)
				)
				(justify right)
			)
		)
	)
	(hierarchical_label "SD{SDIO}"
		(shape bidirectional)
		(at 149.225 106.045 180)
		(effects
			(font
				(size 1.27 1.27)
			)
			(justify right)
		)
	)
	(hierarchical_label "HDMI{TMDS}"
		(shape bidirectional)
		(at 168.91 177.165 180)
		(effects
			(font
				(size 1.27 1.27)
			)
			(justify right)
		)
	)
	(symbol
		(lib_id "antmicropower:GND")
		(at 34.29 267.335 0)
		(mirror y)
		(unit 1)
		(exclude_from_sim no)
		(in_bom yes)
		(on_board yes)
		(dnp no)
		(fields_autoplaced yes)
		(property "Reference" "#PWR0265"
			(at 34.29 273.685 0)
			(effects
				(font
					(size 1.27 1.27)
				)
				(hide yes)
			)
		)
		(property "Value" "GND"
			(at 36.83 268.605 0)
			(effects
				(font
					(size 1.27 1.27)
					(thickness 0.15)
				)
				(justify right)
			)
		)
		(property "Footprint" ""
			(at 25.4 274.955 0)
			(effects
				(font
					(size 1.27 1.27)
					(thickness 0.15)
				)
				(justify left bottom)
				(hide yes)
			)
		)
		(property "Datasheet" ""
			(at 25.4 280.035 0)
			(effects
				(font
					(size 1.27 1.27)
					(thickness 0.15)
				)
				(justify left bottom)
				(hide yes)
			)
		)
		(property "Description" ""
			(at 25.4 282.575 0)
			(effects
				(font
					(size 1.27 1.27)
				)
				(justify left bottom)
				(hide yes)
			)
		)
		(property "Author" "Antmicro"
			(at 25.4 274.955 0)
			(effects
				(font
					(size 1.27 1.27)
					(thickness 0.15)
				)
				(justify left bottom)
				(hide yes)
			)
		)
		(property "License" "Apache-2.0"
			(at 25.4 277.495 0)
			(effects
				(font
					(size 1.27 1.27)
					(thickness 0.15)
				)
				(justify left bottom)
				(hide yes)
			)
		)
		(pin "1"
		)
		(instances
			(project "sodimm-ddr5-tester"
				(path ""
					(reference "#PWR0265")
					(unit 1)
				)
			)
		)
	)
	(symbol
		(lib_id "antmicroCapacitors0402:C_100n_0402")
		(at 26.035 259.715 90)
		(mirror x)
		(unit 1)
		(exclude_from_sim no)
		(in_bom yes)
		(on_board yes)
		(dnp no)
		(fields_autoplaced yes)
		(property "Reference" "C164"
			(at 23.495 260.9913 90)
			(effects
				(font
					(size 1.27 1.27)
				)
				(justify left)
			)
		)
		(property "Value" "C_100n_0402"
			(at 36.195 280.035 0)
			(effects
				(font
					(size 1.27 1.27)
					(thickness 0.15)
				)
				(justify left bottom)
				(hide yes)
			)
		)
		(property "Footprint" "antmicro-footprints:C_0402_1005Metric"
			(at 38.735 280.035 0)
			(effects
				(font
					(size 1.27 1.27)
					(thickness 0.15)
				)
				(justify left bottom)
				(hide yes)
			)
		)
		(property "Datasheet" "https://www.murata.com/products/productdetail?partno=GRM155R61H104KE14%23"
			(at 41.275 280.035 0)
			(effects
				(font
					(size 1.27 1.27)
					(thickness 0.15)
				)
				(justify left bottom)
				(hide yes)
			)
		)
		(property "Description" ""
			(at 26.035 259.715 0)
			(effects
				(font
					(size 1.27 1.27)
				)
			)
		)
		(property "Manufacturer" "Murata"
			(at 46.355 280.035 0)
			(effects
				(font
					(size 1.27 1.27)
					(thickness 0.15)
				)
				(justify left bottom)
				(hide yes)
			)
		)
		(property "MPN" "GRM155R61H104KE14D"
			(at 43.815 280.035 0)
			(effects
				(font
					(size 1.27 1.27)
					(thickness 0.15)
				)
				(justify left bottom)
				(hide yes)
			)
		)
		(property "Val" "100n"
			(at 23.495 264.1662 90)
			(effects
				(font
					(size 1.27 1.27)
					(thickness 0.15)
				)
				(justify left)
			)
		)
		(property "License" "Apache-2.0"
			(at 48.895 280.035 0)
			(effects
				(font
					(size 1.27 1.27)
					(thickness 0.15)
				)
				(justify left bottom)
				(hide yes)
			)
		)
		(property "Author" "Antmicro"
			(at 51.435 280.035 0)
			(effects
				(font
					(size 1.27 1.27)
					(thickness 0.15)
				)
				(justify left bottom)
				(hide yes)
			)
		)
		(property "Voltage" "50V"
			(at 53.975 280.035 0)
			(effects
				(font
					(size 1.27 1.27)
				)
				(justify left bottom)
				(hide yes)
			)
		)
		(property "Dielectric" "X5R"
			(at 56.515 280.035 0)
			(effects
				(font
					(size 1.27 1.27)
				)
				(justify left bottom)
				(hide yes)
			)
		)
		(pin "1"
		)
		(pin "2"
		)
		(instances
			(project "sodimm-ddr5-tester"
				(path ""
					(reference "C164")
					(unit 1)
				)
			)
		)
	)
	(symbol
		(lib_id "antmicroOscillators:Oscillator_100MHz_ASFL1")
		(at 36.83 257.81 0)
		(unit 1)
		(exclude_from_sim no)
		(in_bom yes)
		(on_board yes)
		(dnp no)
		(fields_autoplaced yes)
		(property "Reference" "Y3"
			(at 46.355 249.0612 0)
			(effects
				(font
					(size 1.27 1.27)
					(thickness 0.15)
				)
			)
		)
		(property "Value" "Oscillator_100MHz_ASFL1"
			(at 62.865 269.875 0)
			(effects
				(font
					(size 1.27 1.27)
					(thickness 0.15)
				)
				(justify left bottom)
				(hide yes)
			)
		)
		(property "Footprint" "antmicro-footprints:Oscillator_SMD_Abracon_ASFL1-4Pin_5.0x3.2mm"
			(at 62.865 272.415 0)
			(effects
				(font
					(size 1.27 1.27)
					(thickness 0.15)
				)
				(justify left bottom)
				(hide yes)
			)
		)
		(property "Datasheet" "https://abracon.com/Oscillators/ASFL1.pdf"
			(at 62.865 274.955 0)
			(effects
				(font
					(size 1.27 1.27)
					(thickness 0.15)
				)
				(justify left bottom)
				(hide yes)
			)
		)
		(property "Description" ""
			(at 36.83 257.81 0)
			(effects
				(font
					(size 1.27 1.27)
				)
			)
		)
		(property "MPN" "ASFL1-100.000MHZ-L-T"
			(at 46.355 251.5849 0)
			(effects
				(font
					(size 1.27 1.27)
					(thickness 0.15)
				)
			)
		)
		(property "Manufacturer" "Abracon"
			(at 62.865 264.795 0)
			(effects
				(font
					(size 1.27 1.27)
					(thickness 0.15)
				)
				(justify left bottom)
				(hide yes)
			)
		)
		(property "Val" "100 MHz"
			(at 46.355 254.1086 0)
			(effects
				(font
					(size 1.27 1.27)
					(thickness 0.15)
				)
			)
		)
		(property "Author" "Antmicro"
			(at 62.865 277.495 0)
			(effects
				(font
					(size 1.27 1.27)
					(thickness 0.15)
				)
				(justify left bottom)
				(hide yes)
			)
		)
		(property "License" "Apache-2.0"
			(at 62.865 280.035 0)
			(effects
				(font
					(size 1.27 1.27)
					(thickness 0.15)
				)
				(justify left bottom)
				(hide yes)
			)
		)
		(pin "1"
		)
		(pin "2"
		)
		(pin "3"
		)
		(pin "4"
		)
		(instances
			(project "sodimm-ddr5-tester"
				(path ""
					(reference "Y3")
					(unit 1)
				)
			)
		)
	)
	(symbol
		(lib_id "antmicroFPGAChips:XC7K160T-FFG676")
		(at 185.42 72.39 0)
		(unit 5)
		(exclude_from_sim no)
		(in_bom yes)
		(on_board yes)
		(dnp no)
		(fields_autoplaced yes)
		(property "Reference" "U4"
			(at 219.202 136.3294 0)
			(effects
				(font
					(size 1.27 1.27)
				)
				(justify left)
			)
		)
		(property "Value" "XC7K160T-FFG676"
			(at 219.202 138.8597 0)
			(effects
				(font
					(size 1.27 1.27)
					(thickness 0.15)
				)
				(justify left)
			)
		)
		(property "Footprint" "antmicro-footprints:BGA-676_27x27mm_Layout26x26_P1x1mm_FFG676"
			(at 254 74.93 0)
			(effects
				(font
					(size 1.27 1.27)
					(thickness 0.15)
				)
				(justify left bottom)
				(hide yes)
			)
		)
		(property "Datasheet" "https://docs.xilinx.com/v/u/en-US/ds180_7Series_Overview"
			(at 254 77.47 0)
			(effects
				(font
					(size 1.27 1.27)
					(thickness 0.15)
				)
				(justify left bottom)
				(hide yes)
			)
		)
		(property "Description" ""
			(at 185.42 72.39 0)
			(effects
				(font
					(size 1.27 1.27)
				)
			)
		)
		(property "MPN" "XC7K160T-FFG676"
			(at 185.42 72.39 0)
			(effects
				(font
					(size 1.27 1.27)
				)
				(hide yes)
			)
		)
		(property "Author" "Antmicro"
			(at 254 80.01 0)
			(effects
				(font
					(size 1.27 1.27)
					(thickness 0.15)
				)
				(justify left bottom)
				(hide yes)
			)
		)
		(property "License" "Apache-2.0"
			(at 254 82.55 0)
			(effects
				(font
					(size 1.27 1.27)
					(thickness 0.15)
				)
				(justify left bottom)
				(hide yes)
			)
		)
		(property "Manufacturer" "AMD-Xilinx"
			(at 185.42 72.39 0)
			(effects
				(font
					(size 1.27 1.27)
				)
				(hide yes)
			)
		)
		(pin "AA21"
		)
		(pin "AA22"
		)
		(pin "AA23"
		)
		(pin "AA24"
		)
		(pin "AA25"
		)
		(pin "AB21"
		)
		(pin "AB22"
		)
		(pin "AB24"
		)
		(pin "AB25"
		)
		(pin "AB26"
		)
		(pin "AC21"
		)
		(pin "AC22"
		)
		(pin "AC23"
		)
		(pin "AC24"
		)
		(pin "AC25"
		)
		(pin "AC26"
		)
		(pin "AD21"
		)
		(pin "AD22"
		)
		(pin "AD23"
		)
		(pin "AD24"
		)
		(pin "AD25"
		)
		(pin "AD26"
		)
		(pin "AE21"
		)
		(pin "AE22"
		)
		(pin "AE23"
		)
		(pin "AE25"
		)
		(pin "AE26"
		)
		(pin "AF22"
		)
		(pin "AF23"
		)
		(pin "AF24"
		)
		(pin "AF25"
		)
		(pin "AF26"
		)
		(pin "U21"
		)
		(pin "U22"
		)
		(pin "U23"
		)
		(pin "U24"
		)
		(pin "U25"
		)
		(pin "U26"
		)
		(pin "V20"
		)
		(pin "V21"
		)
		(pin "V22"
		)
		(pin "V23"
		)
		(pin "V24"
		)
		(pin "V26"
		)
		(pin "W20"
		)
		(pin "W21"
		)
		(pin "W23"
		)
		(pin "W24"
		)
		(pin "W25"
		)
		(pin "W26"
		)
		(pin "Y20"
		)
		(pin "Y21"
		)
		(pin "Y22"
		)
		(pin "Y23"
		)
		(pin "Y24"
		)
		(pin "Y25"
		)
		(pin "Y26"
		)
		(pin "K24"
		)
		(pin "K25"
		)
		(pin "K26"
		)
		(pin "L24"
		)
		(pin "L25"
		)
		(pin "M19"
		)
		(pin "M20"
		)
		(pin "M21"
		)
		(pin "M22"
		)
		(pin "M24"
		)
		(pin "M25"
		)
		(pin "M26"
		)
		(pin "N16"
		)
		(pin "N17"
		)
		(pin "N18"
		)
		(pin "N19"
		)
		(pin "N21"
		)
		(pin "N22"
		)
		(pin "N23"
		)
		(pin "N24"
		)
		(pin "N25"
		)
		(pin "N26"
		)
		(pin "P16"
		)
		(pin "P18"
		)
		(pin "P19"
		)
		(pin "P20"
		)
		(pin "P21"
		)
		(pin "P22"
		)
		(pin "P23"
		)
		(pin "P24"
		)
		(pin "P25"
		)
		(pin "P26"
		)
		(pin "R16"
		)
		(pin "R17"
		)
		(pin "R18"
		)
		(pin "R19"
		)
		(pin "R20"
		)
		(pin "R21"
		)
		(pin "R22"
		)
		(pin "R23"
		)
		(pin "R25"
		)
		(pin "R26"
		)
		(pin "T16"
		)
		(pin "T17"
		)
		(pin "T18"
		)
		(pin "T19"
		)
		(pin "T20"
		)
		(pin "T22"
		)
		(pin "T23"
		)
		(pin "T24"
		)
		(pin "T25"
		)
		(pin "T26"
		)
		(pin "U16"
		)
		(pin "U17"
		)
		(pin "U19"
		)
		(pin "U20"
		)
		(pin "A20"
		)
		(pin "A21"
		)
		(pin "A22"
		)
		(pin "A23"
		)
		(pin "A24"
		)
		(pin "A25"
		)
		(pin "B20"
		)
		(pin "B21"
		)
		(pin "B22"
		)
		(pin "B24"
		)
		(pin "B25"
		)
		(pin "B26"
		)
		(pin "C21"
		)
		(pin "C22"
		)
		(pin "C23"
		)
		(pin "C24"
		)
		(pin "C25"
		)
		(pin "C26"
		)
		(pin "D21"
		)
		(pin "D22"
		)
		(pin "D23"
		)
		(pin "D24"
		)
		(pin "D25"
		)
		(pin "D26"
		)
		(pin "E21"
		)
		(pin "E22"
		)
		(pin "E23"
		)
		(pin "E25"
		)
		(pin "E26"
		)
		(pin "F22"
		)
		(pin "F23"
		)
		(pin "F24"
		)
		(pin "F25"
		)
		(pin "F26"
		)
		(pin "G21"
		)
		(pin "G22"
		)
		(pin "G23"
		)
		(pin "G24"
		)
		(pin "G25"
		)
		(pin "G26"
		)
		(pin "H21"
		)
		(pin "H22"
		)
		(pin "H23"
		)
		(pin "H24"
		)
		(pin "H26"
		)
		(pin "J21"
		)
		(pin "J23"
		)
		(pin "J24"
		)
		(pin "J25"
		)
		(pin "J26"
		)
		(pin "K21"
		)
		(pin "K22"
		)
		(pin "K23"
		)
		(pin "L21"
		)
		(pin "L22"
		)
		(pin "L23"
		)
		(pin "A17"
		)
		(pin "A18"
		)
		(pin "A19"
		)
		(pin "B16"
		)
		(pin "B17"
		)
		(pin "B18"
		)
		(pin "B19"
		)
		(pin "C16"
		)
		(pin "C17"
		)
		(pin "C18"
		)
		(pin "C19"
		)
		(pin "D15"
		)
		(pin "D16"
		)
		(pin "D18"
		)
		(pin "D19"
		)
		(pin "D20"
		)
		(pin "E15"
		)
		(pin "E16"
		)
		(pin "E17"
		)
		(pin "E18"
		)
		(pin "E19"
		)
		(pin "E20"
		)
		(pin "F15"
		)
		(pin "F16"
		)
		(pin "F17"
		)
		(pin "F18"
		)
		(pin "F19"
		)
		(pin "F20"
		)
		(pin "G15"
		)
		(pin "G16"
		)
		(pin "G17"
		)
		(pin "G19"
		)
		(pin "G20"
		)
		(pin "H16"
		)
		(pin "H17"
		)
		(pin "H18"
		)
		(pin "H19"
		)
		(pin "H20"
		)
		(pin "J15"
		)
		(pin "J16"
		)
		(pin "J17"
		)
		(pin "J18"
		)
		(pin "J19"
		)
		(pin "J20"
		)
		(pin "K15"
		)
		(pin "K16"
		)
		(pin "K17"
		)
		(pin "K18"
		)
		(pin "K20"
		)
		(pin "L17"
		)
		(pin "L18"
		)
		(pin "L19"
		)
		(pin "L20"
		)
		(pin "M16"
		)
		(pin "M17"
		)
		(pin "M18"
		)
		(pin "A10"
		)
		(pin "A11"
		)
		(pin "A12"
		)
		(pin "A13"
		)
		(pin "A14"
		)
		(pin "A15"
		)
		(pin "A8"
		)
		(pin "A9"
		)
		(pin "B10"
		)
		(pin "B11"
		)
		(pin "B12"
		)
		(pin "B14"
		)
		(pin "B15"
		)
		(pin "B8"
		)
		(pin "B9"
		)
		(pin "C11"
		)
		(pin "C12"
		)
		(pin "C13"
		)
		(pin "C14"
		)
		(pin "C15"
		)
		(pin "C9"
		)
		(pin "D10"
		)
		(pin "D11"
		)
		(pin "D12"
		)
		(pin "D13"
		)
		(pin "D14"
		)
		(pin "D8"
		)
		(pin "D9"
		)
		(pin "E10"
		)
		(pin "E11"
		)
		(pin "E12"
		)
		(pin "E13"
		)
		(pin "E9"
		)
		(pin "F10"
		)
		(pin "F12"
		)
		(pin "F13"
		)
		(pin "F14"
		)
		(pin "F8"
		)
		(pin "F9"
		)
		(pin "G10"
		)
		(pin "G11"
		)
		(pin "G12"
		)
		(pin "G13"
		)
		(pin "G14"
		)
		(pin "G9"
		)
		(pin "H10"
		)
		(pin "H11"
		)
		(pin "H12"
		)
		(pin "H13"
		)
		(pin "H14"
		)
		(pin "H8"
		)
		(pin "H9"
		)
		(pin "J10"
		)
		(pin "J11"
		)
		(pin "J13"
		)
		(pin "J14"
		)
		(pin "J8"
		)
		(pin "AA14"
		)
		(pin "AA15"
		)
		(pin "AA17"
		)
		(pin "AA18"
		)
		(pin "AA19"
		)
		(pin "AA20"
		)
		(pin "AB14"
		)
		(pin "AB15"
		)
		(pin "AB16"
		)
		(pin "AB17"
		)
		(pin "AB18"
		)
		(pin "AB19"
		)
		(pin "AB20"
		)
		(pin "AC14"
		)
		(pin "AC15"
		)
		(pin "AC16"
		)
		(pin "AC17"
		)
		(pin "AC18"
		)
		(pin "AC19"
		)
		(pin "AD14"
		)
		(pin "AD15"
		)
		(pin "AD16"
		)
		(pin "AD18"
		)
		(pin "AD19"
		)
		(pin "AD20"
		)
		(pin "AE15"
		)
		(pin "AE16"
		)
		(pin "AE17"
		)
		(pin "AE18"
		)
		(pin "AE19"
		)
		(pin "AE20"
		)
		(pin "AF14"
		)
		(pin "AF15"
		)
		(pin "AF16"
		)
		(pin "AF17"
		)
		(pin "AF18"
		)
		(pin "AF19"
		)
		(pin "AF20"
		)
		(pin "V13"
		)
		(pin "V14"
		)
		(pin "V16"
		)
		(pin "V17"
		)
		(pin "V18"
		)
		(pin "V19"
		)
		(pin "W13"
		)
		(pin "W14"
		)
		(pin "W15"
		)
		(pin "W16"
		)
		(pin "W17"
		)
		(pin "W18"
		)
		(pin "W19"
		)
		(pin "Y14"
		)
		(pin "Y15"
		)
		(pin "Y16"
		)
		(pin "Y17"
		)
		(pin "Y18"
		)
		(pin "AA10"
		)
		(pin "AA11"
		)
		(pin "AA12"
		)
		(pin "AA13"
		)
		(pin "AA7"
		)
		(pin "AA8"
		)
		(pin "AA9"
		)
		(pin "AB10"
		)
		(pin "AB11"
		)
		(pin "AB12"
		)
		(pin "AB7"
		)
		(pin "AB8"
		)
		(pin "AB9"
		)
		(pin "AC11"
		)
		(pin "AC12"
		)
		(pin "AC13"
		)
		(pin "AC7"
		)
		(pin "AC8"
		)
		(pin "AC9"
		)
		(pin "AD10"
		)
		(pin "AD11"
		)
		(pin "AD12"
		)
		(pin "AD13"
		)
		(pin "AD8"
		)
		(pin "AD9"
		)
		(pin "AE10"
		)
		(pin "AE11"
		)
		(pin "AE12"
		)
		(pin "AE13"
		)
		(pin "AE7"
		)
		(pin "AE8"
		)
		(pin "AE9"
		)
		(pin "AF10"
		)
		(pin "AF12"
		)
		(pin "AF13"
		)
		(pin "AF7"
		)
		(pin "AF8"
		)
		(pin "AF9"
		)
		(pin "U9"
		)
		(pin "V10"
		)
		(pin "V11"
		)
		(pin "V12"
		)
		(pin "V7"
		)
		(pin "V8"
		)
		(pin "V9"
		)
		(pin "W10"
		)
		(pin "W11"
		)
		(pin "W7"
		)
		(pin "W8"
		)
		(pin "W9"
		)
		(pin "Y10"
		)
		(pin "Y11"
		)
		(pin "Y12"
		)
		(pin "Y13"
		)
		(pin "Y7"
		)
		(pin "Y8"
		)
		(pin "AA1"
		)
		(pin "AA2"
		)
		(pin "AA3"
		)
		(pin "AA4"
		)
		(pin "AA5"
		)
		(pin "AB1"
		)
		(pin "AB2"
		)
		(pin "AB4"
		)
		(pin "AB5"
		)
		(pin "AB6"
		)
		(pin "AC1"
		)
		(pin "AC2"
		)
		(pin "AC3"
		)
		(pin "AC4"
		)
		(pin "AC5"
		)
		(pin "AC6"
		)
		(pin "AD1"
		)
		(pin "AD2"
		)
		(pin "AD3"
		)
		(pin "AD4"
		)
		(pin "AD5"
		)
		(pin "AD6"
		)
		(pin "AE1"
		)
		(pin "AE2"
		)
		(pin "AE3"
		)
		(pin "AE5"
		)
		(pin "AE6"
		)
		(pin "AF2"
		)
		(pin "AF3"
		)
		(pin "AF4"
		)
		(pin "AF5"
		)
		(pin "AF6"
		)
		(pin "T7"
		)
		(pin "U1"
		)
		(pin "U2"
		)
		(pin "U3"
		)
		(pin "U4"
		)
		(pin "U5"
		)
		(pin "U6"
		)
		(pin "U7"
		)
		(pin "V1"
		)
		(pin "V2"
		)
		(pin "V3"
		)
		(pin "V4"
		)
		(pin "V6"
		)
		(pin "W1"
		)
		(pin "W3"
		)
		(pin "W4"
		)
		(pin "W5"
		)
		(pin "W6"
		)
		(pin "Y1"
		)
		(pin "Y2"
		)
		(pin "Y3"
		)
		(pin "Y4"
		)
		(pin "Y5"
		)
		(pin "Y6"
		)
		(pin "A3"
		)
		(pin "A4"
		)
		(pin "B1"
		)
		(pin "B2"
		)
		(pin "B5"
		)
		(pin "B6"
		)
		(pin "C3"
		)
		(pin "C4"
		)
		(pin "D1"
		)
		(pin "D2"
		)
		(pin "D5"
		)
		(pin "D6"
		)
		(pin "E3"
		)
		(pin "E4"
		)
		(pin "F1"
		)
		(pin "F2"
		)
		(pin "F5"
		)
		(pin "F6"
		)
		(pin "G3"
		)
		(pin "G4"
		)
		(pin "H1"
		)
		(pin "H2"
		)
		(pin "H5"
		)
		(pin "H6"
		)
		(pin "J3"
		)
		(pin "J4"
		)
		(pin "K1"
		)
		(pin "K2"
		)
		(pin "K5"
		)
		(pin "K6"
		)
		(pin "L3"
		)
		(pin "L4"
		)
		(pin "M1"
		)
		(pin "M2"
		)
		(pin "N3"
		)
		(pin "N4"
		)
		(pin "P1"
		)
		(pin "P2"
		)
		(pin "R3"
		)
		(pin "R4"
		)
		(pin "A1"
		)
		(pin "A16"
		)
		(pin "A2"
		)
		(pin "A26"
		)
		(pin "A5"
		)
		(pin "A6"
		)
		(pin "A7"
		)
		(pin "AA16"
		)
		(pin "AA26"
		)
		(pin "AA6"
		)
		(pin "AB13"
		)
		(pin "AB23"
		)
		(pin "AB3"
		)
		(pin "AC10"
		)
		(pin "AC20"
		)
		(pin "AD17"
		)
		(pin "AD7"
		)
		(pin "AE14"
		)
		(pin "AE24"
		)
		(pin "AE4"
		)
		(pin "AF1"
		)
		(pin "AF11"
		)
		(pin "AF21"
		)
		(pin "B13"
		)
		(pin "B23"
		)
		(pin "B3"
		)
		(pin "B4"
		)
		(pin "B7"
		)
		(pin "C1"
		)
		(pin "C10"
		)
		(pin "C2"
		)
		(pin "C20"
		)
		(pin "C5"
		)
		(pin "C6"
		)
		(pin "C7"
		)
		(pin "D17"
		)
		(pin "D3"
		)
		(pin "D4"
		)
		(pin "D7"
		)
		(pin "E1"
		)
		(pin "E14"
		)
		(pin "E2"
		)
		(pin "E24"
		)
		(pin "E5"
		)
		(pin "E6"
		)
		(pin "E7"
		)
		(pin "E8"
		)
		(pin "F11"
		)
		(pin "F21"
		)
		(pin "F3"
		)
		(pin "F4"
		)
		(pin "F7"
		)
		(pin "G1"
		)
		(pin "G18"
		)
		(pin "G2"
		)
		(pin "G5"
		)
		(pin "G6"
		)
		(pin "G8"
		)
		(pin "H15"
		)
		(pin "H25"
		)
		(pin "H3"
		)
		(pin "H4"
		)
		(pin "H7"
		)
		(pin "J1"
		)
		(pin "J12"
		)
		(pin "J2"
		)
		(pin "J22"
		)
		(pin "J5"
		)
		(pin "J6"
		)
		(pin "J9"
		)
		(pin "K10"
		)
		(pin "K11"
		)
		(pin "K12"
		)
		(pin "K13"
		)
		(pin "K14"
		)
		(pin "K19"
		)
		(pin "K3"
		)
		(pin "K4"
		)
		(pin "K7"
		)
		(pin "K8"
		)
		(pin "K9"
		)
		(pin "L1"
		)
		(pin "L10"
		)
		(pin "L11"
		)
		(pin "L12"
		)
		(pin "L13"
		)
		(pin "L14"
		)
		(pin "L15"
		)
		(pin "L16"
		)
		(pin "L2"
		)
		(pin "L26"
		)
		(pin "L5"
		)
		(pin "L6"
		)
		(pin "L9"
		)
		(pin "M10"
		)
		(pin "M11"
		)
		(pin "M12"
		)
		(pin "M13"
		)
		(pin "M14"
		)
		(pin "M15"
		)
		(pin "M23"
		)
		(pin "M3"
		)
		(pin "M4"
		)
		(pin "M5"
		)
		(pin "M6"
		)
		(pin "M7"
		)
		(pin "M8"
		)
		(pin "M9"
		)
		(pin "N1"
		)
		(pin "N10"
		)
		(pin "N13"
		)
		(pin "N14"
		)
		(pin "N15"
		)
		(pin "N2"
		)
		(pin "N20"
		)
		(pin "N5"
		)
		(pin "N6"
		)
		(pin "N7"
		)
		(pin "N9"
		)
		(pin "P10"
		)
		(pin "P13"
		)
		(pin "P14"
		)
		(pin "P15"
		)
		(pin "P17"
		)
		(pin "P3"
		)
		(pin "P4"
		)
		(pin "P8"
		)
		(pin "P9"
		)
		(pin "R1"
		)
		(pin "R10"
		)
		(pin "R13"
		)
		(pin "R14"
		)
		(pin "R15"
		)
		(pin "R2"
		)
		(pin "R24"
		)
		(pin "R5"
		)
		(pin "R8"
		)
		(pin "R9"
		)
		(pin "T1"
		)
		(pin "T10"
		)
		(pin "T11"
		)
		(pin "T12"
		)
		(pin "T13"
		)
		(pin "T14"
		)
		(pin "T15"
		)
		(pin "T21"
		)
		(pin "T3"
		)
		(pin "T4"
		)
		(pin "T8"
		)
		(pin "T9"
		)
		(pin "U10"
		)
		(pin "U11"
		)
		(pin "U12"
		)
		(pin "U13"
		)
		(pin "U14"
		)
		(pin "U15"
		)
		(pin "U18"
		)
		(pin "U8"
		)
		(pin "V15"
		)
		(pin "V25"
		)
		(pin "V5"
		)
		(pin "W12"
		)
		(pin "W2"
		)
		(pin "W22"
		)
		(pin "Y19"
		)
		(pin "Y9"
		)
		(pin "C8"
		)
		(pin "G7"
		)
		(pin "J7"
		)
		(pin "L7"
		)
		(pin "L8"
		)
		(pin "N11"
		)
		(pin "N12"
		)
		(pin "N8"
		)
		(pin "P11"
		)
		(pin "P12"
		)
		(pin "P5"
		)
		(pin "P6"
		)
		(pin "P7"
		)
		(pin "R11"
		)
		(pin "R12"
		)
		(pin "R6"
		)
		(pin "R7"
		)
		(pin "T2"
		)
		(pin "T5"
		)
		(pin "T6"
		)
		(instances
			(project "sodimm-ddr5-tester"
				(path ""
					(reference "U4")
					(unit 5)
				)
			)
		)
	)
	(symbol
		(lib_id "antmicropower:+3V3")
		(at 26.035 255.905 0)
		(unit 1)
		(exclude_from_sim no)
		(in_bom yes)
		(on_board yes)
		(dnp no)
		(fields_autoplaced yes)
		(property "Reference" "#PWR0263"
			(at 26.035 259.715 0)
			(effects
				(font
					(size 1.27 1.27)
				)
				(hide yes)
			)
		)
		(property "Value" "+3V3"
			(at 22.86 253.365 0)
			(effects
				(font
					(size 1.27 1.27)
					(thickness 0.15)
				)
				(justify left bottom)
			)
		)
		(property "Footprint" ""
			(at 41.275 263.525 0)
			(effects
				(font
					(size 1.27 1.27)
					(thickness 0.15)
				)
				(justify left bottom)
				(hide yes)
			)
		)
		(property "Datasheet" ""
			(at 41.275 266.065 0)
			(effects
				(font
					(size 1.27 1.27)
					(thickness 0.15)
				)
				(justify left bottom)
				(hide yes)
			)
		)
		(property "Description" ""
			(at 26.035 255.905 0)
			(effects
				(font
					(size 1.27 1.27)
				)
			)
		)
		(property "Author" "Antmicro"
			(at 41.275 258.445 0)
			(effects
				(font
					(size 1.27 1.27)
					(thickness 0.15)
				)
				(justify left bottom)
				(hide yes)
			)
		)
		(property "License" "Apache-2.0"
			(at 41.275 260.985 0)
			(effects
				(font
					(size 1.27 1.27)
					(thickness 0.15)
				)
				(justify left bottom)
				(hide yes)
			)
		)
		(pin "1"
		)
		(instances
			(project "sodimm-ddr5-tester"
				(path ""
					(reference "#PWR0263")
					(unit 1)
				)
			)
		)
	)
	(symbol
		(lib_id "antmicropower:GND")
		(at 26.035 267.335 0)
		(mirror y)
		(unit 1)
		(exclude_from_sim no)
		(in_bom yes)
		(on_board yes)
		(dnp no)
		(fields_autoplaced yes)
		(property "Reference" "#PWR0264"
			(at 26.035 273.685 0)
			(effects
				(font
					(size 1.27 1.27)
				)
				(hide yes)
			)
		)
		(property "Value" "GND"
			(at 27.94 268.605 0)
			(effects
				(font
					(size 1.27 1.27)
					(thickness 0.15)
				)
				(justify right)
			)
		)
		(property "Footprint" ""
			(at 17.145 274.955 0)
			(effects
				(font
					(size 1.27 1.27)
					(thickness 0.15)
				)
				(justify left bottom)
				(hide yes)
			)
		)
		(property "Datasheet" ""
			(at 17.145 280.035 0)
			(effects
				(font
					(size 1.27 1.27)
					(thickness 0.15)
				)
				(justify left bottom)
				(hide yes)
			)
		)
		(property "Description" ""
			(at 17.145 282.575 0)
			(effects
				(font
					(size 1.27 1.27)
				)
				(justify left bottom)
				(hide yes)
			)
		)
		(property "Author" "Antmicro"
			(at 17.145 274.955 0)
			(effects
				(font
					(size 1.27 1.27)
					(thickness 0.15)
				)
				(justify left bottom)
				(hide yes)
			)
		)
		(property "License" "Apache-2.0"
			(at 17.145 277.495 0)
			(effects
				(font
					(size 1.27 1.27)
					(thickness 0.15)
				)
				(justify left bottom)
				(hide yes)
			)
		)
		(pin "1"
		)
		(instances
			(project "sodimm-ddr5-tester"
				(path ""
					(reference "#PWR0264")
					(unit 1)
				)
			)
		)
	)
	(symbol
		(lib_id "antmicropower:+3V3")
		(at 184.15 71.12 0)
		(unit 1)
		(exclude_from_sim no)
		(in_bom yes)
		(on_board yes)
		(dnp no)
		(fields_autoplaced yes)
		(property "Reference" "#PWR0262"
			(at 184.15 74.93 0)
			(effects
				(font
					(size 1.27 1.27)
				)
				(hide yes)
			)
		)
		(property "Value" "+3V3"
			(at 180.975 68.58 0)
			(effects
				(font
					(size 1.27 1.27)
					(thickness 0.15)
				)
				(justify left bottom)
			)
		)
		(property "Footprint" ""
			(at 199.39 78.74 0)
			(effects
				(font
					(size 1.27 1.27)
					(thickness 0.15)
				)
				(justify left bottom)
				(hide yes)
			)
		)
		(property "Datasheet" ""
			(at 199.39 81.28 0)
			(effects
				(font
					(size 1.27 1.27)
					(thickness 0.15)
				)
				(justify left bottom)
				(hide yes)
			)
		)
		(property "Description" ""
			(at 184.15 71.12 0)
			(effects
				(font
					(size 1.27 1.27)
				)
			)
		)
		(property "Author" "Antmicro"
			(at 199.39 73.66 0)
			(effects
				(font
					(size 1.27 1.27)
					(thickness 0.15)
				)
				(justify left bottom)
				(hide yes)
			)
		)
		(property "License" "Apache-2.0"
			(at 199.39 76.2 0)
			(effects
				(font
					(size 1.27 1.27)
					(thickness 0.15)
				)
				(justify left bottom)
				(hide yes)
			)
		)
		(pin "1"
		)
		(instances
			(project "sodimm-ddr5-tester"
				(path ""
					(reference "#PWR0262")
					(unit 1)
				)
			)
		)
	)
)
